(kicad_pcb
	(version 20260206)
	(generator "pcbnew")
	(generator_version "10.0")
	(general
		(thickness 1.6)
		(legacy_teardrops no)
	)
	(paper "A4")
	(title_block
		(title "pdpb — Lightning_PDPB_BRD.brd")
		(comment 1 "Lightning (Wiwynn / Facebook NVMe JBOF) / footprints 345-351 of 1140")
	)
	(layers
		(0 "F.Cu" signal "TOP")
		(4 "In1.Cu" signal "L2GND")
		(6 "In2.Cu" signal "L3")
		(8 "In3.Cu" signal "L4VCC")
		(10 "In4.Cu" signal "L5VCC")
		(12 "In5.Cu" signal "L6")
		(14 "In6.Cu" signal "L7GND")
		(2 "B.Cu" signal "BOTTOM")
		(9 "F.Adhes" user "F.Adhesive")
		(11 "B.Adhes" user "B.Adhesive")
		(13 "F.Paste" user "Package Geometry/Pastemask Top")
		(15 "B.Paste" user "Package Geometry/Pastemask Bottom")
		(5 "F.SilkS" user "Ref Des/Silkscreen Top")
		(7 "B.SilkS" user "Ref Des/Silkscreen Bottom")
		(1 "F.Mask" user "Board Geometry/Soldermask Top")
		(3 "B.Mask" user "Board Geometry/Soldermask Bottom")
		(17 "Dwgs.User" user "User.Drawings")
		(19 "Cmts.User" user "User.Comments")
		(21 "Eco1.User" user "User.Eco1")
		(23 "Eco2.User" user "User.Eco2")
		(25 "Edge.Cuts" user "Board Geometry/Outline")
		(27 "Margin" user)
		(31 "F.CrtYd" user "Package Geometry/Place Bound Top")
		(29 "B.CrtYd" user "Package Geometry/Place Bound Bottom")
		(35 "F.Fab" user "Ref Des/Assembly Top")
		(33 "B.Fab" user "Ref Des/Assembly Bottom")
	)
	(footprint ""
		(layer "F.Cu")
		(at 49.061116 -342.007952 90)
		(property "Reference" "R9821"
			(at 0 0 90)
			(layer "F.SilkS")
			(hide yes)
			(effects
				(font
					(size 1.27 1.27)
				)
			)
		)
		(property "Value" "0R2J-2-GP"
			(at 0.064008 -3.993896 90)
			(unlocked yes)
			(layer "F.Fab")
			(hide yes)
			(effects
				(font
					(size 1.016 1.016)
					(thickness 0.1524)
				)
			)
		)
		(property "Device Type" "R402H16"
			(at 0.064008 -5.517896 90)
			(unlocked yes)
			(layer "F.Fab")
			(hide yes)
			(effects
				(font
					(size 1.016 1.016)
					(thickness 0.1524)
				)
			)
		)
		(duplicate_pad_numbers_are_jumpers no)
		(fp_line
			(start 0.508 -0.9398)
			(end -0.508 -0.9398)
			(stroke
				(width 0.1524)
				(type default)
			)
			(layer "F.SilkS")
		)
		(fp_line
			(start -0.508 -0.9398)
			(end -0.508 0.9398)
			(stroke
				(width 0.1524)
				(type default)
			)
			(layer "F.SilkS")
		)
		(fp_rect
			(start -0.508 0.9398)
			(end 0.508 -0.9398)
			(stroke
				(width 0)
				(type default)
			)
			(fill no)
			(layer "F.CrtYd")
		)
		(fp_rect
			(start -0.508 0.9398)
			(end 0.508 -0.9398)
			(stroke
				(width 0)
				(type default)
			)
			(fill no)
			(layer "F.Fab")
		)
		(pad "1" smd custom
			(at 0 -0.4445 90)
			(size 0.1397 0.1397)
			(layers "F.Cu" "F.Mask" "F.Paste")
			(net "ATTN_LED_DR6_AND")
			(options
				(clearance outline)
				(anchor circle)
			)
			(primitives
				(gr_poly
					(pts
						(arc
							(start -0.1778 -0.2794)
							(mid -0.249642 -0.249642)
							(end -0.2794 -0.1778)
						)
						(arc
							(start -0.2794 0.1778)
							(mid -0.249642 0.249642)
							(end -0.1778 0.2794)
						)
						(arc
							(start 0.1778 0.2794)
							(mid 0.249642 0.249642)
							(end 0.2794 0.1778)
						)
						(arc
							(start 0.2794 -0.1778)
							(mid 0.249642 -0.249642)
							(end 0.1778 -0.2794)
						)
					)
					(width 0)
					(fill yes)
				)
			)
		)
		(pad "2" smd custom
			(at 0 0.4445 90)
			(size 0.1397 0.1397)
			(layers "F.Cu" "F.Mask" "F.Paste")
			(net "ATTN_LED_DR6_AND_R")
			(options
				(clearance outline)
				(anchor circle)
			)
			(primitives
				(gr_poly
					(pts
						(arc
							(start -0.1778 -0.2794)
							(mid -0.249642 -0.249642)
							(end -0.2794 -0.1778)
						)
						(arc
							(start -0.2794 0.1778)
							(mid -0.249642 0.249642)
							(end -0.1778 0.2794)
						)
						(arc
							(start 0.1778 0.2794)
							(mid 0.249642 0.249642)
							(end 0.2794 0.1778)
						)
						(arc
							(start 0.2794 -0.1778)
							(mid 0.249642 -0.249642)
							(end 0.1778 -0.2794)
						)
					)
					(width 0)
					(fill yes)
				)
			)
		)
	)
	(footprint ""
		(layer "F.Cu")
		(at 43.50004 -247.10009)
		(property "Reference" "LED7"
			(at 0 0 0)
			(layer "F.SilkS")
			(hide yes)
			(effects
				(font
					(size 1.27 1.27)
				)
			)
		)
		(property "Value" "LED-RB-4-GP"
			(at 5.88899 1.80848 0)
			(unlocked yes)
			(layer "F.Fab")
			(hide yes)
			(effects
				(font
					(size 1.016 1.016)
					(thickness 0.1524)
				)
			)
		)
		(property "Device Type" "LED1613-4PH20"
			(at 5.88899 0.28448 0)
			(unlocked yes)
			(layer "F.Fab")
			(hide yes)
			(effects
				(font
					(size 1.016 1.016)
					(thickness 0.1524)
				)
			)
		)
		(duplicate_pad_numbers_are_jumpers no)
		(fp_line
			(start -1.4478 -0.9652)
			(end 1.4478 -0.9652)
			(stroke
				(width 0.1524)
				(type default)
			)
			(layer "F.SilkS")
		)
		(fp_line
			(start -1.4478 0.9652)
			(end -1.4478 -0.9652)
			(stroke
				(width 0.1524)
				(type default)
			)
			(layer "F.SilkS")
		)
		(fp_line
			(start -1.4478 0.9652)
			(end -1.4478 -0.9652)
			(stroke
				(width 0.508)
				(type default)
			)
			(layer "F.SilkS")
		)
		(fp_line
			(start 1.4478 -0.9652)
			(end 1.4478 0.9652)
			(stroke
				(width 0.1524)
				(type default)
			)
			(layer "F.SilkS")
		)
		(fp_line
			(start 1.4478 0.9652)
			(end -1.4478 0.9652)
			(stroke
				(width 0.1524)
				(type default)
			)
			(layer "F.SilkS")
		)
		(fp_rect
			(start -0.8001 0.6477)
			(end 0.8001 -0.6477)
			(stroke
				(width 0)
				(type default)
			)
			(fill no)
			(layer "F.CrtYd")
		)
		(fp_poly
			(pts
				(xy -1.7018 1.2192) (xy -1.7018 -0.06223) (xy -0.8001 -0.06223) (xy -0.8001 0.6477) (xy 0.8001 0.6477)
				(xy 0.8001 -0.6477) (xy -0.8001 -0.6477) (xy -0.8001 -0.0635) (xy -1.7018 -0.0635) (xy -1.7018 -1.2192)
				(xy 1.7018 -1.2192) (xy 1.7018 1.2192)
			)
			(stroke
				(width 0)
				(type default)
			)
			(fill no)
			(layer "F.CrtYd")
		)
		(fp_rect
			(start -1.7018 1.2192)
			(end 1.7018 -1.2192)
			(stroke
				(width 0)
				(type default)
			)
			(fill no)
			(layer "F.Fab")
		)
		(pad "1" smd rect
			(at -0.73025 0.4064)
			(size 0.9144 0.6096)
			(layers "F.Cu" "F.Mask" "F.Paste")
			(net "SSD_ACT_DR7_MOS_N")
		)
		(pad "2" smd rect
			(at -0.73025 -0.4064)
			(size 0.9144 0.6096)
			(layers "F.Cu" "F.Mask" "F.Paste")
			(net "ATTN_LED_DR7_MOS_N")
		)
		(pad "3" smd rect
			(at 0.73025 -0.4064)
			(size 0.9144 0.6096)
			(layers "F.Cu" "F.Mask" "F.Paste")
			(net "DRV_ATTN_7")
		)
		(pad "4" smd rect
			(at 0.73025 0.4064)
			(size 0.9144 0.6096)
			(layers "F.Cu" "F.Mask" "F.Paste")
			(net "DRV_ACT_7")
		)
	)
	(footprint ""
		(layer "F.Cu")
		(at 220.0402 -86.487)
		(property "Reference" "PC1201"
			(at 0 0 0)
			(layer "F.SilkS")
			(hide yes)
			(effects
				(font
					(size 1.27 1.27)
				)
			)
		)
		(property "Value" "SC22U25V6KX-GP-U"
			(at -2.860802 -5.279644 0)
			(unlocked yes)
			(layer "F.Fab")
			(hide yes)
			(effects
				(font
					(size 1.016 1.016)
					(thickness 0.1524)
				)
			)
		)
		(property "Device Type" "C1206-TO0D3H75"
			(at -2.860802 -6.803644 0)
			(unlocked yes)
			(layer "F.Fab")
			(hide yes)
			(effects
				(font
					(size 1.016 1.016)
					(thickness 0.1524)
				)
			)
		)
		(duplicate_pad_numbers_are_jumpers no)
		(fp_line
			(start -1.3081 -2.3749)
			(end 1.3081 -2.3749)
			(stroke
				(width 0.1524)
				(type default)
			)
			(layer "F.SilkS")
		)
		(fp_line
			(start -1.3081 2.3749)
			(end -1.3081 -2.3749)
			(stroke
				(width 0.1524)
				(type default)
			)
			(layer "F.SilkS")
		)
		(fp_line
			(start 1.3081 -2.3749)
			(end 1.3081 2.3749)
			(stroke
				(width 0.1524)
				(type default)
			)
			(layer "F.SilkS")
		)
		(fp_line
			(start 1.3081 2.3749)
			(end -1.3081 2.3749)
			(stroke
				(width 0.1524)
				(type default)
			)
			(layer "F.SilkS")
		)
		(fp_rect
			(start -0.8001 1.6002)
			(end 0.8001 -1.6002)
			(stroke
				(width 0)
				(type default)
			)
			(fill no)
			(layer "F.CrtYd")
		)
		(fp_poly
			(pts
				(xy -1.5621 2.4511) (xy -1.5621 1.6002) (xy 0.8001 1.6002) (xy 0.8001 -1.6002) (xy -0.8001 -1.6002)
				(xy -0.8001 1.5875) (xy -1.5621 1.5875) (xy -1.5621 -2.4511) (xy 1.5621 -2.4511) (xy 1.5621 2.4511)
			)
			(stroke
				(width 0)
				(type default)
			)
			(fill no)
			(layer "F.CrtYd")
		)
		(fp_rect
			(start -1.5621 2.4511)
			(end 1.5621 -2.4511)
			(stroke
				(width 0)
				(type default)
			)
			(fill no)
			(layer "F.Fab")
		)
		(pad "1" smd rect
			(at 0 -1.392936)
			(size 2.1082 1.4478)
			(layers "F.Cu" "F.Mask" "F.Paste")
			(net "P12V_SSD4")
		)
		(pad "2" smd rect
			(at 0 1.392936)
			(size 2.1082 1.4478)
			(layers "F.Cu" "F.Mask" "F.Paste")
			(net "GND")
		)
	)
	(footprint ""
		(layer "F.Cu")
		(at 232.029 -432.562 -90)
		(property "Reference" "PR9077"
			(at 0 0 270)
			(layer "F.SilkS")
			(hide yes)
			(effects
				(font
					(size 1.27 1.27)
				)
			)
		)
		(property "Value" "10KR2F-2-GP"
			(at 0.064008 -3.993896 270)
			(unlocked yes)
			(layer "F.Fab")
			(hide yes)
			(effects
				(font
					(size 1.016 1.016)
					(thickness 0.1524)
				)
			)
		)
		(property "Device Type" "R402H16"
			(at 0.064008 -5.517896 270)
			(unlocked yes)
			(layer "F.Fab")
			(hide yes)
			(effects
				(font
					(size 1.016 1.016)
					(thickness 0.1524)
				)
			)
		)
		(duplicate_pad_numbers_are_jumpers no)
		(fp_line
			(start -0.508 -0.9398)
			(end -0.508 0.9398)
			(stroke
				(width 0.1524)
				(type default)
			)
			(layer "F.SilkS")
		)
		(fp_line
			(start 0.508 -0.9398)
			(end -0.508 -0.9398)
			(stroke
				(width 0.1524)
				(type default)
			)
			(layer "F.SilkS")
		)
		(fp_rect
			(start -0.508 0.9398)
			(end 0.508 -0.9398)
			(stroke
				(width 0)
				(type default)
			)
			(fill no)
			(layer "F.CrtYd")
		)
		(fp_rect
			(start -0.508 0.9398)
			(end 0.508 -0.9398)
			(stroke
				(width 0)
				(type default)
			)
			(fill no)
			(layer "F.Fab")
		)
		(pad "1" smd custom
			(at 0 -0.4445 270)
			(size 0.1397 0.1397)
			(layers "F.Cu" "F.Mask" "F.Paste")
			(net "AGND_P3V3")
			(options
				(clearance outline)
				(anchor circle)
			)
			(primitives
				(gr_poly
					(pts
						(arc
							(start -0.1778 -0.2794)
							(mid -0.249642 -0.249642)
							(end -0.2794 -0.1778)
						)
						(arc
							(start -0.2794 0.1778)
							(mid -0.249642 0.249642)
							(end -0.1778 0.2794)
						)
						(arc
							(start 0.1778 0.2794)
							(mid 0.249642 0.249642)
							(end 0.2794 0.1778)
						)
						(arc
							(start 0.2794 -0.1778)
							(mid 0.249642 -0.249642)
							(end 0.1778 -0.2794)
						)
					)
					(width 0)
					(fill yes)
				)
			)
		)
		(pad "2" smd custom
			(at 0 0.4445 270)
			(size 0.1397 0.1397)
			(layers "F.Cu" "F.Mask" "F.Paste")
			(net "P3V3_VFB")
			(options
				(clearance outline)
				(anchor circle)
			)
			(primitives
				(gr_poly
					(pts
						(arc
							(start -0.1778 -0.2794)
							(mid -0.249642 -0.249642)
							(end -0.2794 -0.1778)
						)
						(arc
							(start -0.2794 0.1778)
							(mid -0.249642 0.249642)
							(end -0.1778 0.2794)
						)
						(arc
							(start 0.1778 0.2794)
							(mid 0.249642 0.249642)
							(end 0.2794 0.1778)
						)
						(arc
							(start 0.2794 -0.1778)
							(mid 0.249642 -0.249642)
							(end 0.1778 -0.2794)
						)
					)
					(width 0)
					(fill yes)
				)
			)
		)
	)
	(footprint ""
		(layer "F.Cu")
		(at 28.1432 -393.2428 -90)
		(property "Reference" "SR1104"
			(at 0 0 270)
			(layer "F.SilkS")
			(hide yes)
			(effects
				(font
					(size 1.27 1.27)
				)
			)
		)
		(property "Value" "4K7R2F-GP"
			(at 0.064008 -3.993896 270)
			(unlocked yes)
			(layer "F.Fab")
			(hide yes)
			(effects
				(font
					(size 1.016 1.016)
					(thickness 0.1524)
				)
			)
		)
		(property "Device Type" "R402H16"
			(at 0.064008 -5.517896 270)
			(unlocked yes)
			(layer "F.Fab")
			(hide yes)
			(effects
				(font
					(size 1.016 1.016)
					(thickness 0.1524)
				)
			)
		)
		(duplicate_pad_numbers_are_jumpers no)
		(fp_line
			(start -0.508 -0.9398)
			(end -0.508 0.9398)
			(stroke
				(width 0.1524)
				(type default)
			)
			(layer "F.SilkS")
		)
		(fp_line
			(start 0.508 -0.9398)
			(end -0.508 -0.9398)
			(stroke
				(width 0.1524)
				(type default)
			)
			(layer "F.SilkS")
		)
		(fp_rect
			(start -0.508 0.9398)
			(end 0.508 -0.9398)
			(stroke
				(width 0)
				(type default)
			)
			(fill no)
			(layer "F.CrtYd")
		)
		(fp_rect
			(start -0.508 0.9398)
			(end 0.508 -0.9398)
			(stroke
				(width 0)
				(type default)
			)
			(fill no)
			(layer "F.Fab")
		)
		(pad "1" smd custom
			(at 0 -0.4445 270)
			(size 0.1397 0.1397)
			(layers "F.Cu" "F.Mask" "F.Paste")
			(net "DUALPORTEN#6")
			(options
				(clearance outline)
				(anchor circle)
			)
			(primitives
				(gr_poly
					(pts
						(arc
							(start -0.1778 -0.2794)
							(mid -0.249642 -0.249642)
							(end -0.2794 -0.1778)
						)
						(arc
							(start -0.2794 0.1778)
							(mid -0.249642 0.249642)
							(end -0.1778 0.2794)
						)
						(arc
							(start 0.1778 0.2794)
							(mid 0.249642 0.249642)
							(end 0.2794 0.1778)
						)
						(arc
							(start 0.2794 -0.1778)
							(mid 0.249642 -0.249642)
							(end 0.1778 -0.2794)
						)
					)
					(width 0)
					(fill yes)
				)
			)
		)
		(pad "2" smd custom
			(at 0 0.4445 270)
			(size 0.1397 0.1397)
			(layers "F.Cu" "F.Mask" "F.Paste")
			(net "GND")
			(options
				(clearance outline)
				(anchor circle)
			)
			(primitives
				(gr_poly
					(pts
						(arc
							(start -0.1778 -0.2794)
							(mid -0.249642 -0.249642)
							(end -0.2794 -0.1778)
						)
						(arc
							(start -0.2794 0.1778)
							(mid -0.249642 0.249642)
							(end -0.1778 0.2794)
						)
						(arc
							(start 0.1778 0.2794)
							(mid 0.249642 0.249642)
							(end 0.2794 0.1778)
						)
						(arc
							(start 0.2794 -0.1778)
							(mid 0.249642 -0.249642)
							(end 0.1778 -0.2794)
						)
					)
					(width 0)
					(fill yes)
				)
			)
		)
	)
	(footprint ""
		(layer "F.Cu")
		(at 9.2329 -384.0988 180)
		(property "Reference" "C9536"
			(at 0 0 180)
			(layer "F.SilkS")
			(hide yes)
			(effects
				(font
					(size 1.27 1.27)
				)
			)
		)
		(property "Value" "SCD01U50V2KX-1GP"
			(at 1.1811 -2.7051 180)
			(unlocked yes)
			(layer "F.Fab")
			(hide yes)
			(effects
				(font
					(size 1.016 1.016)
					(thickness 0.1524)
				)
			)
		)
		(property "Device Type" "C402H22"
			(at 1.1811 -4.2291 180)
			(unlocked yes)
			(layer "F.Fab")
			(hide yes)
			(effects
				(font
					(size 1.016 1.016)
					(thickness 0.1524)
				)
			)
		)
		(duplicate_pad_numbers_are_jumpers no)
		(fp_rect
			(start -0.4318 0.9525)
			(end 0.4318 -0.9525)
			(stroke
				(width 0)
				(type default)
			)
			(fill no)
			(layer "F.CrtYd")
		)
		(fp_rect
			(start -0.4318 0.9525)
			(end 0.4318 -0.9525)
			(stroke
				(width 0)
				(type default)
			)
			(fill no)
			(layer "F.Fab")
		)
		(pad "1" smd custom
			(at 0 -0.4445 180)
			(size 0.1524 0.1524)
			(layers "F.Cu" "F.Mask" "F.Paste")
			(net "PE_100M_CLK2_P")
			(options
				(clearance outline)
				(anchor circle)
			)
			(primitives
				(gr_poly
					(pts
						(arc
							(start 0.3048 -0.2032)
							(mid 0.275042 -0.275042)
							(end 0.2032 -0.3048)
						)
						(arc
							(start -0.2032 -0.3048)
							(mid -0.275042 -0.275042)
							(end -0.3048 -0.2032)
						)
						(arc
							(start -0.3048 0.2032)
							(mid -0.275042 0.275042)
							(end -0.2032 0.3048)
						)
						(arc
							(start 0.2032 0.3048)
							(mid 0.275042 0.275042)
							(end 0.3048 0.2032)
						)
					)
					(width 0)
					(fill yes)
				)
			)
		)
		(pad "2" smd custom
			(at 0 0.4445 180)
			(size 0.1524 0.1524)
			(layers "F.Cu" "F.Mask" "F.Paste")
			(net "PE_100M_CLK2_C_P")
			(options
				(clearance outline)
				(anchor circle)
			)
			(primitives
				(gr_poly
					(pts
						(arc
							(start 0.3048 -0.2032)
							(mid 0.275042 -0.275042)
							(end 0.2032 -0.3048)
						)
						(arc
							(start -0.2032 -0.3048)
							(mid -0.275042 -0.275042)
							(end -0.3048 -0.2032)
						)
						(arc
							(start -0.3048 0.2032)
							(mid -0.275042 0.275042)
							(end -0.2032 0.3048)
						)
						(arc
							(start 0.2032 0.3048)
							(mid 0.275042 0.275042)
							(end 0.3048 0.2032)
						)
					)
					(width 0)
					(fill yes)
				)
			)
		)
	)
	(footprint ""
		(layer "F.Cu")
		(at 215.9 -197.9676 -90)
		(property "Reference" "Q41"
			(at 0 0 270)
			(layer "F.SilkS")
			(hide yes)
			(effects
				(font
					(size 1.27 1.27)
				)
			)
		)
		(property "Value" "2N7002A-7-GP"
			(at 0.127 -8.9662 270)
			(unlocked yes)
			(layer "F.Fab")
			(hide yes)
			(effects
				(font
					(size 1.016 1.016)
					(thickness 0.1524)
				)
			)
		)
		(property "Device Type" "SOT23DGS2D4H48"
			(at 0.127 -10.4902 270)
			(unlocked yes)
			(layer "F.Fab")
			(hide yes)
			(effects
				(font
					(size 1.016 1.016)
					(thickness 0.1524)
				)
			)
		)
		(duplicate_pad_numbers_are_jumpers no)
		(fp_line
			(start -1.651 1.778)
			(end 1.651 1.778)
			(stroke
				(width 0.1524)
				(type default)
			)
			(layer "F.SilkS")
		)
		(fp_line
			(start 1.651 1.778)
			(end 1.651 -1.778)
			(stroke
				(width 0.1524)
				(type default)
			)
			(layer "F.SilkS")
		)
		(fp_line
			(start -1.651 -1.778)
			(end -1.651 1.778)
			(stroke
				(width 0.1524)
				(type default)
			)
			(layer "F.SilkS")
		)
		(fp_line
			(start 1.651 -1.778)
			(end -1.651 -1.778)
			(stroke
				(width 0.1524)
				(type default)
			)
			(layer "F.SilkS")
		)
		(fp_poly
			(pts
				(xy -1.778 1.8796) (xy -1.778 -1.8796) (xy 1.778 -1.8796) (xy 1.778 1.8796)
			)
			(stroke
				(width 0)
				(type default)
			)
			(fill no)
			(layer "F.CrtYd")
		)
		(fp_poly
			(pts
				(xy -1.778 1.8796) (xy -1.778 -1.8796) (xy 1.778 -1.8796) (xy 1.778 1.8796)
			)
			(stroke
				(width 0)
				(type default)
			)
			(fill no)
			(layer "F.Fab")
		)
		(pad "D" smd custom
			(at 0 -0.9525 270)
			(size 0.1905 0.1905)
			(layers "F.Cu" "F.Mask" "F.Paste")
			(net "P12V_MOST3_GATE_D")
			(options
				(clearance outline)
				(anchor circle)
			)
			(primitives
				(gr_poly
					(pts
						(arc
							(start -0.1778 0.5715)
							(mid -0.321484 0.511984)
							(end -0.381 0.3683)
						)
						(arc
							(start -0.381 -0.3683)
							(mid -0.321484 -0.511984)
							(end -0.1778 -0.5715)
						)
						(arc
							(start 0.1778 -0.5715)
							(mid 0.321484 -0.511984)
							(end 0.381 -0.3683)
						)
						(arc
							(start 0.381 0.3683)
							(mid 0.321484 0.511984)
							(end 0.1778 0.5715)
						)
					)
					(width 0)
					(fill yes)
				)
			)
		)
		(pad "G" smd custom
			(at -0.98425 0.9525 270)
			(size 0.1905 0.1905)
			(layers "F.Cu" "F.Mask" "F.Paste")
			(net "P12V_MOST3_GATE")
			(options
				(clearance outline)
				(anchor circle)
			)
			(primitives
				(gr_poly
					(pts
						(arc
							(start -0.1778 0.5715)
							(mid -0.321484 0.511984)
							(end -0.381 0.3683)
						)
						(arc
							(start -0.381 -0.3683)
							(mid -0.321484 -0.511984)
							(end -0.1778 -0.5715)
						)
						(arc
							(start 0.1778 -0.5715)
							(mid 0.321484 -0.511984)
							(end 0.381 -0.3683)
						)
						(arc
							(start 0.381 0.3683)
							(mid 0.321484 0.511984)
							(end 0.1778 0.5715)
						)
					)
					(width 0)
					(fill yes)
				)
			)
		)
		(pad "S" smd custom
			(at 0.98425 0.9525 270)
			(size 0.1905 0.1905)
			(layers "F.Cu" "F.Mask" "F.Paste")
			(net "GND")
			(options
				(clearance outline)
				(anchor circle)
			)
			(primitives
				(gr_poly
					(pts
						(arc
							(start -0.1778 0.5715)
							(mid -0.321484 0.511984)
							(end -0.381 0.3683)
						)
						(arc
							(start -0.381 -0.3683)
							(mid -0.321484 -0.511984)
							(end -0.1778 -0.5715)
						)
						(arc
							(start 0.1778 -0.5715)
							(mid 0.321484 -0.511984)
							(end 0.381 -0.3683)
						)
						(arc
							(start 0.381 0.3683)
							(mid 0.321484 0.511984)
							(end 0.1778 0.5715)
						)
					)
					(width 0)
					(fill yes)
				)
			)
		)
	)
)
